FILE_TYPE = CONNECTIVITY;
{Allegro Design Entry HDL 16.6-p007 (v16-6-112F) 10/10/2012}
"PAGE_NUMBER" = 231;
0"NC";
1"PVPP_ABC\g";
2"GND\g";
3"AGND_PVPP_ABC\g";
4"GND\g";
5"GND\g";
6"GND\g";
7"P12V_STBY\g";
8"AGND_PVPP_ABC\g";
9"GND\g";
10"AGND_PVPP_ABC\g";
11"GND\g";
12"GND\g";
13"GND\g";
14"GND\g";
15"GND\g";
16"PVPP_ABC\g";
17"AGND_PVPP_ABC\g";
18"AGND_PVPP_ABC\g";
19"P3V3_STBY\g";
20"AGND_PVPP_ABC\g";
21"GND\g";
22"AGND_PVPP_ABC\g";
23"AGND_PVPP_ABC\g";
24"GND\g";
25"GND\g";
26"GND\g";
27"GND\g";
28"GND\g";
29"GND\g";
30"GND\g";
31"VR_FET_SW_P12V_STBY_PVPP_ABC";
32"FM_PVPP_PVDDQ_CPU0_EN_ABC";
33"VR_FB_PVPP_ABC";
34"VR_COMP_RC_PVPP_ABC";
35"VR_COMP_PVPP_ABC_3";
36"FM_PVPP_CPU0_EN";
37"VR_COMP_PVPP_ABC";
38"PWRGD_PVPP_ABC";
39"VR_PVPP_ABC_BOOT_R";
40"VR_PVPP_ABC_SNUB";
41"VR_PVPP_ABC_PHASE";
42"VR_PVPP_ABC_BOOT";
43"VR_PVPP_ABC_SS";
44"VR_VB_PVPP_ABC";
45"PWRGD_PVPP_ABC_R";
46"VR_PVPP_ABC_ISET";
47"VSENSE_PVPP_ABC";
%"CAP"
"1","(-7925,1000)","0","mstr_discrete","I122";
;
GROUP"PWR_MLCC_CAP"
PART_NUMBER"E15431-001"
MATERIAL"X6S"
VALUE"10UF"
LOCATION"C6F6"
VOLTAGE"4V"
TOLERANCE"20%"
PACK_TYPE"0603LF"
CDS_LIB"mstr_discrete"
CDS_LOCATION"C6F6"
CDS_SEC"1"
$SEC"1"
BOM_COST"MEM_VRD_PVPP_AB"
ROOM"PVPP_KLM_VR";
"A"
$PN"1"1;
"B"
$PN"2"5;
%"PVPP_ABC"
"1","(-7925,1250)","0","mstr_symbols","I123";
;
HDL_POWER"PVPP_ABC"
BODY_TYPE"PLUMBING"
ROOM"PVPP_KLM_VR"
BOM_COST"MEM_VRD_PVPP_AB"
CDS_LIB"mstr_symbols"
VOLTAGE"2.5V";
"G\NAC"1;
%"CAP"
"1","(-7625,1000)","0","mstr_discrete","I124";
;
GROUP"PWR_MLCC_CAP"
PART_NUMBER"E15431-001"
VOLTAGE"4V"
LOCATION"C4T6"
VALUE"10UF"
TOLERANCE"20%"
MATERIAL"X6S"
PACK_TYPE"0603LF"
CDS_LIB"mstr_discrete"
ROOM"PVPP_KLM_VR"
CDS_LOCATION"C4T6"
$SEC"1"
CDS_SEC"1"
BOM_COST"MEM_VRD_PVPP_AB";
"A"
$PN"1"1;
"B"
$PN"2"5;
%"CAP"
"1","(-7350,1000)","0","mstr_discrete","I125";
;
GROUP"PWR_MLCC_CAP"
PART_NUMBER"E15431-001"
VOLTAGE"4V"
PACK_TYPE"0603LF"
LOCATION"C4T5"
VALUE"10UF"
TOLERANCE"20%"
MATERIAL"X6S"
BOM_COST"MEM_VRD_PVPP_AB"
$SEC"1"
CDS_SEC"1"
ROOM"PVPP_KLM_VR"
CDS_LOCATION"C4T5"
CDS_LIB"mstr_discrete";
"A"
$PN"1"1;
"B"
$PN"2"5;
%"CAP"
"1","(-7075,975)","0","mstr_discrete","I126";
;
GROUP"PWR_MLCC_CAP"
LOCATION"C6G1"
VALUE"10UF"
TOLERANCE"20%"
MATERIAL"X6S"
PART_NUMBER"E15431-001"
PACK_TYPE"0603LF"
VOLTAGE"4V"
BOM_COST"MEM_VRD_PVPP_AB"
CDS_SEC"1"
$SEC"1"
CDS_LOCATION"C6G1"
ROOM"PVPP_KLM_VR"
CDS_LIB"mstr_discrete";
"A"
$PN"1"1;
"B"
$PN"2"5;
%"GND"
"1","(-6625,2200)","0","mstr_symbols","I127";
;
HDL_POWER"GND"
BODY_TYPE"PLUMBING"
VOLTAGE"0"
SIZE"1B"
CDS_LIB"mstr_symbols"
BOM_COST"PVPP_KLM_VR"
BOM"SYSB_CPLD"
ROOM"PVPP_KLM_VR";
"A\NAC"2;
%"CAP"
"1","(-6800,1000)","0","mstr_discrete","I128";
;
GROUP"PWR_MLCC_CAP"
TOLERANCE"20%"
VOLTAGE"4V"
LOCATION"C6G2"
PACK_TYPE"0603LF"
VALUE"10UF"
PART_NUMBER"E15431-001"
MATERIAL"X6S"
BOM_COST"MEM_VRD_PVPP_AB"
CDS_SEC"1"
$SEC"1"
CDS_LOCATION"C6G2"
ROOM"PVPP_KLM_VR"
CDS_LIB"mstr_discrete";
"A"
$PN"1"1;
"B"
$PN"2"5;
%"CAP"
"1","(-6500,1000)","0","mstr_discrete","I129";
;
GROUP"PWR_MLCC_CAP"
PACK_TYPE"0603LF"
VALUE"10UF"
LOCATION"C4U2"
PART_NUMBER"E15431-001"
MATERIAL"X6S"
VOLTAGE"4V"
TOLERANCE"20%"
$SEC"1"
CDS_SEC"1"
ROOM"PVPP_KLM_VR"
BOM_COST"MEM_VRD_PVPP_AB"
CDS_LOCATION"C4U2"
CDS_LIB"mstr_discrete";
"A"
$PN"1"1;
"B"
$PN"2"5;
%"CAP"
"1","(-6225,1000)","0","mstr_discrete","I130";
;
PART_NUMBER"E15431-001"
GROUP"PWR_MLCC_CAP"
VOLTAGE"4V"
PACK_TYPE"0603LF"
VALUE"10UF"
MATERIAL"X6S"
LOCATION"C4U1"
TOLERANCE"20%"
$SEC"1"
CDS_SEC"1"
ROOM"PVPP_KLM_VR"
BOM_COST"MEM_VRD_PVPP_AB"
CDS_LOCATION"C4U1"
CDS_LIB"mstr_discrete";
"A"
$PN"1"1;
"B"
$PN"2"5;
%"CAP"
"1","(-5925,1000)","0","mstr_discrete","I131";
;
GROUP"PWR_MLCC_CAP"
MATERIAL"X6S"
PART_NUMBER"E15431-001"
PACK_TYPE"0603LF"
LOCATION"C6G4"
VOLTAGE"4V"
VALUE"10UF"
TOLERANCE"20%"
BOM_COST"MEM_VRD_PVPP_AB"
CDS_SEC"1"
$SEC"1"
CDS_LOCATION"C6G4"
ROOM"PVPP_KLM_VR"
CDS_LIB"mstr_discrete";
"A"
$PN"1"1;
"B"
$PN"2"5;
%"AGND_SCSI"
"1","(-6175,2325)","0","mstr_symbols","I132";
;
HDL_POWER"AGND_PVPP_ABC"
BODY_TYPE"PLUMBING"
CDS_LIB"mstr_symbols"
BOM_COST"PVPP_KLM_VR"
ROOM"PVPP_KLM_VR"
VOLTAGE"0.0V";
"A"3;
%"RES"
"2","(-4400,1900)","2","mstr_discrete","I134";
;
TOLERANCE"1.0%"
WATTAGE"1/16W"
CONFIG"64.39015.6DL"
NEW_VALUE"3.9K"
LOCATION"R7F15"
PACK_TYPE"0402"
MATERIAL"CHIP"
PART_NUMBER"G21796-242"
VALUE"7.87K"
ROOM"PVPP_KLM_VR"
BOM_COST"PVPP_KLM_VR"
CDS_LIB"mstr_discrete"
CDS_LOCATION"R7F15"
$SEC"1"
CDS_SEC"1";
"A"
$PN"1"46;
"B"
$PN"2"18;
%"RES"
"2","(-6625,2450)","0","mstr_discrete","I136";
;
LOCATION"R7F14"
VALUE"10.0K"
PACK_TYPE"0402"
TOLERANCE"1%"
WATTAGE"1/16W"
MATERIAL"CHIP"
PART_NUMBER"G21796-016"
BOM"SYSB_CPLD"
BOM_COST"PVPP_KLM_VR"
CDS_SEC"1"
$SEC"1"
CDS_LOCATION"R7F14"
ROOM"PVPP_KLM_VR"
CDS_LIB"mstr_discrete";
"A"
$PN"1"36;
"B"
$PN"2"2;
%"CAP"
"1","(-6175,2650)","2","mstr_discrete","I140";
;
VALUE"1000PF"
VOLTAGE"50V"
TOLERANCE"10%"
MATERIAL"EMPTY"
PART_NUMBER"A36096-046"
PACK_TYPE"0402LF"
LOCATION"C7F8"
FIN"VR_1P2"
REUSE_ID"1"
CDS_SEC"1"
$SEC"1"
CDS_LOCATION"C7F8"
CDS_LIB"mstr_discrete"
BOM_COST"PVPP_KLM_VR"
ROOM"PVPP_KLM_VR";
"A"
$PN"1"36;
"B"
$PN"2"3;
%"GND"
"1","(-3700,775)","0","mstr_symbols","I141";
;
HDL_POWER"GND"
BODY_TYPE"PLUMBING"
CDS_LIB"mstr_symbols"
VOLTAGE"0"
SIZE"1B"
BOM_COST"PVPP_KLM_VR"
ROOM"PVPP_KLM_VR";
"A\NAC"4;
%"CAP"
"1","(-3700,1050)","0","mstr_discrete","I142";
;
VALUE"1000PF"
LOCATION"C7F11"
MATERIAL"X7R"
VOLTAGE"50V"
TOLERANCE"10%"
PART_NUMBER"A36096-046"
PACK_TYPE"0402LF"
ROOM"PVPP_KLM_VR"
CDS_LIB"mstr_discrete"
BOM_COST"PVPP_KLM_VR"
CDS_LOCATION"C7F11"
$SEC"1"
CDS_SEC"1"
REUSE_ID"17";
"A"
$PN"1"45;
"B"
$PN"2"4;
%"RES"
"2","(-3875,1500)","0","mstr_discrete","I143";
;
CDS_SEC"1"
LOCATION"R7F19"
PART_NUMBER"G21796-026"
VALUE"1.00K"
PACK_TYPE"0402"
MATERIAL"CHIP"
TOLERANCE"1%"
WATTAGE"1/16W"
SEC_TYPE"0402"
BOM_COST"PVPP_KLM_VR"
REUSE_ID"21"
SEC"1"
CDS_LOCATION"R7F19"
ROOM"PVPP_KLM_VR"
CDS_LIB"mstr_discrete";
"A"
$PN"1"19;
"B"
$PN"2"45;
%"CAP"
"1","(-5625,1000)","0","mstr_discrete","I145";
;
GROUP"PWR_MLCC_CAP"
PART_NUMBER"E15431-001"
PACK_TYPE"0603LF"
MATERIAL"X6S"
TOLERANCE"20%"
VOLTAGE"4V"
VALUE"10UF"
LOCATION"C6G5"
BOM_COST"MEM_VRD_PVPP_AB"
CDS_SEC"1"
$SEC"1"
CDS_LOCATION"C6G5"
ROOM"PVPP_KLM_VR"
CDS_LIB"mstr_discrete";
"A"
$PN"1"1;
"B"
$PN"2"5;
%"CAP"
"1","(-5350,975)","0","mstr_discrete","I146";
;
GROUP"PWR_MLCC_CAP"
LOCATION"C4U4"
VALUE"10UF"
VOLTAGE"4V"
TOLERANCE"20%"
MATERIAL"X6S"
PART_NUMBER"E15431-001"
PACK_TYPE"0603LF"
CDS_SEC"1"
$SEC"1"
BOM_COST"MEM_VRD_PVPP_AB"
ROOM"PVPP_KLM_VR"
CDS_LOCATION"C4U4"
CDS_LIB"mstr_discrete";
"A"
$PN"1"1;
"B"
$PN"2"5;
%"GND"
"1","(-7925,575)","0","mstr_symbols","I147";
;
ROOM"PVPP_KLM_VR"
BOM_COST"MEM_VRD_PVPP_AB"
CDS_LIB"mstr_symbols"
VOLTAGE"0"
SIZE"1B"
BODY_TYPE"PLUMBING"
HDL_POWER"GND";
"A\NAC"5;
%"CAP"
"1","(-5075,975)","0","mstr_discrete","I148";
;
PART_NUMBER"E15431-001"
PACK_TYPE"0603LF"
VOLTAGE"4V"
VALUE"10UF"
LOCATION"C4U3"
MATERIAL"X6S"
TOLERANCE"20%"
GROUP"PWR_MLCC_CAP"
$SEC"1"
CDS_SEC"1"
ROOM"PVPP_KLM_VR"
BOM_COST"MEM_VRD_PVPP_AB"
CDS_LOCATION"C4U3"
CDS_LIB"mstr_discrete";
"A"
$PN"1"1;
"B"
$PN"2"5;
%"CAP"
"1","(-4800,975)","0","mstr_discrete","I149";
;
CDS_SEC"1"
MATERIAL"X6S"
PACK_TYPE"0603LF"
PART_NUMBER"E15431-001"
VALUE"10UF"
LOCATION"C6F5"
GROUP"PWR_MLCC_CAP"
TOLERANCE"20%"
VOLTAGE"4V"
CDS_LIB"mstr_discrete"
ROOM"PVPP_KLM_VR"
CDS_LOCATION"C6F5"
SEC"1"
SEC_TYPE"0603LF"
BOM_COST"MEM_VRD_PVPP_AB";
"A"
$PN"1"1;
"B"
$PN"2"5;
%"CAP"
"2","(-3025,4450)","2","mstr_discrete","I159";
;
MATERIAL"X7R"
TOLERANCE"10%"
VALUE"0.1UF"
PACK_TYPE"0603LF"
VOLTAGE"25V"
LOCATION"C7F4"
PART_NUMBER"602433-020"
$SEC"1"
BOM_COST"PVPP_KLM_VR"
SPOF"TRUE"
CDS_SEC"1"
REUSE_ID"27"
CDS_LOCATION"C7F4"
ROOM"PVPP_KLM_VR"
CDS_LIB"mstr_discrete";
"A"
$PN"1"41;
"B"
$PN"2"39;
%"GND"
"1","(-4700,4150)","0","mstr_symbols","I160";
;
HDL_POWER"GND"
BODY_TYPE"PLUMBING"
SIZE"1B"
CDS_LIB"mstr_symbols"
VOLTAGE"0"
BOM_COST"PVPP_KLM_VR"
ROOM"PVPP_KLM_VR";
"A\NAC"6;
%"CAP"
"1","(-4700,4400)","0","mstr_discrete","I161";
;
PART_NUMBER"D97712-011"
MATERIAL"X6S"
TOLERANCE"10%"
VOLTAGE"16V"
VALUE"1.0UF"
LOCATION"C3T10"
PACK_TYPE"0402"
CDS_LIB"mstr_discrete"
CDS_LOCATION"C3T10"
BOM_COST"PVPP_KLM_VR"
ROOM"PVPP_KLM_VR"
REUSE_ID"1"
CDS_SEC"1"
$SEC"1"
FIN"VR_1P2";
"A"
$PN"1"31;
"B"
$PN"2"6;
%"FERRITE"
"1","(-7300,4550)","0","mstr_discrete","I162";
;
CDS_SEC"1"
VALUE"22"
PART_NUMBER"656554-051"
PACK_TYPE"SM"
MATERIAL"FB"
LOCATION"FB7F1"
SEC_TYPE"SM"
TOLERANCE"1%"
SEC"1"
ROOM"PVPP_KLM_VR"
CDS_LOCATION"FB7F1"
CDS_LIB"mstr_discrete";
"A"
$PN"1"7;
"B"
$PN"2"31;
%"P12V_STBY"
"1","(-7500,4650)","0","mstr_symbols","I163";
;
HDL_POWER"P12V_STBY"
BODY_TYPE"PLUMBING"
SIZE"1B"
VOLTAGE"12.0V"
CDS_LIB"mstr_symbols";
"G\NAC"7;
%"AGND_SCSI"
"1","(-1000,1250)","0","mstr_symbols","I165";
;
HDL_POWER"AGND_PVPP_ABC"
BODY_TYPE"PLUMBING"
ROOM"PVPP_KLM_VR"
BOM_COST"PVPP_KLM_VR"
VOLTAGE"0.0V"
CDS_LIB"mstr_symbols";
"A"8;
%"RES"
"2","(-1000,2250)","0","mstr_discrete","I167";
;
TOLERANCE"1%"
PART_NUMBER"G21796-040"
MATERIAL"CHIP"
PACK_TYPE"0402"
WATTAGE"1/16W"
VALUE"20.0K"
LOCATION"R7F13"
CDS_LIB"mstr_discrete"
CDS_LOCATION"R7F13"
ROOM"PVPP_KLM_VR"
$SEC"1"
CDS_SEC"1"
BOM_COST"PVPP_KLM_VR"
REUSE_ID"9"
SPOF"TRUE";
"A"
$PN"1"47;
"B"
$PN"2"33;
%"RES"
"1","(-1000,3175)","5","mstr_discrete","I168";
;
CDS_SEC"1"
PART_NUMBER"G21497-005"
PACK_TYPE"0402"
MATERIAL"CHIP"
TOLERANCE"5%"
WATTAGE"1/16W"
VALUE"0.0"
LOCATION"R7F12"
SEC"1"
SPOF"TRUE"
SEC_TYPE"0402"
ROOM"PVPP_KLM_VR"
CDS_LIB"mstr_discrete"
CDS_LOCATION"R7F12";
"B"
$PN"2"47;
"A"
$PN"1"16;
%"GND"
"1","(-1250,625)","0","mstr_symbols","I169";
;
HDL_POWER"GND"
BODY_TYPE"PLUMBING"
CDS_LIB"mstr_symbols"
SIZE"1B"
VOLTAGE"0"
ROOM"PVPP_KLM_VR"
BOM_COST"PVPP_KLM_VR";
"A\NAC"9;
%"RES"
"1","(-950,725)","0","mstr_discrete","I170";
;
CDS_LOCATION"R7F35"
WATTAGE"1/16W"
MATERIAL"CHIP"
TOLERANCE"5%"
VALUE"0.0"
PACK_TYPE"0402"
LOCATION"R7F35"
PART_NUMBER"G21497-005"
ROOM"PVPP_KLM_VR"
$SEC"1"
CDS_SEC"1"
CDS_LIB"mstr_discrete";
"B"
$PN"2"10;
"A"
$PN"1"9;
%"AGND_SCSI"
"1","(-700,625)","0","mstr_symbols","I171";
;
HDL_POWER"AGND_PVPP_ABC"
BODY_TYPE"PLUMBING"
VOLTAGE"0.0V"
CDS_LIB"mstr_symbols"
BOM_COST"PVPP_KLM_VR"
ROOM"PVPP_KLM_VR";
"A"10;
%"GND"
"1","(-2300,3400)","0","mstr_symbols","I173";
;
HDL_POWER"GND"
BODY_TYPE"PLUMBING"
VOLTAGE"0"
CDS_LIB"mstr_symbols"
SIZE"1B"
ROOM"PVPP_KLM_VR"
BOM_COST"PVPP_KLM_VR";
"A\NAC"11;
%"RES"
"2","(-2300,3600)","0","mstr_discrete","I174";
;
WATTAGE"1/16W"
PACK_TYPE"0402"
MATERIAL"EMPTY"
LOCATION"R7F7"
VALUE"2.2"
TOLERANCE"5%"
PART_NUMBER"G21497-016"
REUSE_ID"29"
CDS_SEC"1"
$SEC"1"
BOM_COST"PVPP_KLM_VR"
ROOM"PVPP_KLM_VR"
CDS_LOCATION"R7F7"
CDS_LIB"mstr_discrete";
"A"
$PN"1"40;
"B"
$PN"2"11;
%"CAP"
"1","(-2300,3950)","0","mstr_discrete","I175";
;
VALUE"3300PF"
TOLERANCE"10%"
LOCATION"C7F3"
VOLTAGE"50V"
MATERIAL"EMPTY"
PACK_TYPE"0402LF"
PART_NUMBER"A36096-091"
BOM_COST"PVPP_KLM_VR"
REUSE_ID"26"
CDS_SEC"1"
$SEC"1"
ROOM"PVPP_KLM_VR"
CDS_LOCATION"C7F3"
CDS_LIB"mstr_discrete";
"A"
$PN"1"41;
"B"
$PN"2"40;
%"GND"
"1","(-1725,3675)","0","mstr_symbols","I176";
;
HDL_POWER"GND"
BODY_TYPE"PLUMBING"
SIZE"1B"
CDS_LIB"mstr_symbols"
VOLTAGE"0"
ROOM"PVPP_KLM_VR"
BOM_COST"PVPP_KLM_VR";
"A\NAC"12;
%"RES"
"2","(-1725,3925)","0","mstr_discrete","I177";
;
CDS_SEC"1"
PART_NUMBER"G22026-003"
LOCATION"R7F10"
VALUE"120.0"
WATTAGE"1/10W"
MATERIAL"CHIP"
TOLERANCE"1%"
PACK_TYPE"0603"
SEC_TYPE"0603"
BOM_COST"PVPP_KLM_VR"
REUSE_ID"34"
SEC"1"
ROOM"PVPP_KLM_VR"
CDS_LOCATION"R7F10"
CDS_LIB"mstr_discrete";
"A"
$PN"1"16;
"B"
$PN"2"12;
%"INDUCTOR"
"1","(-1950,4100)","0","mstr_discrete","I178";
;
PART_NUMBER"E13358-018"
LOCATION"L7F1"
MATERIAL"IND"
PACK_TYPE"SM"
VALUE"0.47UH"
ROOM"PVPP_KLM_VR"
CDS_LOCATION"L7F1"
BOM_COST"PVPP_KLM_VR"
CDS_LIB"mstr_discrete"
REUSE_ID"30"
CDS_SEC"1"
$SEC"1"
TOLERANCE"1%";
"INA\NAC"
$PN"1"41;
"INB\NAC"
$PN"2"16;
%"GND"
"1","(-1400,3525)","0","mstr_symbols","I179";
;
HDL_POWER"GND"
BODY_TYPE"PLUMBING"
VOLTAGE"0"
CDS_LIB"mstr_symbols"
SIZE"1B"
ROOM"PVPP_KLM_VR"
BOM_COST"PVPP_KLM_VR";
"A\NAC"13;
%"CAPP"
"1","(-1400,3900)","0","mstr_discrete","I180";
;
PART_NUMBER"724613-042"
VOLTAGE"6.3V"
TOLERANCE"20%"
VALUE"330UF"
LOCATION"C6F4"
GROUP"PWR_BULK_CAP"
PACK_TYPE"7343LF"
MATERIAL"POSCAP"
REUSE_ID"28"
CDS_SEC"1"
$SEC"1"
CDS_LOCATION"C6F4"
ROOM"PVPP_KLM_VR"
BOM_COST"PVPP_KLM_VR"
CDS_LIB"mstr_discrete";
"B"
$PN"2"13;
"A"
$PN"1"16;
%"GND"
"1","(-775,3525)","0","mstr_symbols","I183";
;
SIZE"1B"
VOLTAGE"0"
CDS_LIB"mstr_symbols"
ROOM"PVPP_KLM_VR"
BOM_COST"PVPP_KLM_VR"
BODY_TYPE"PLUMBING"
HDL_POWER"GND";
"A\NAC"14;
%"CAP"
"1","(-775,3900)","0","mstr_discrete","I184";
;
MATERIAL"X6S"
TOLERANCE"20%"
VOLTAGE"4V"
LOCATION"C3T7"
VALUE"47UF"
PART_NUMBER"C95333-006"
PACK_TYPE"0805"
GROUP"PWR_MLCC_CAP"
ROOM"PVPP_KLM_VR"
BOM_COST"PVPP_KLM_VR"
CDS_LIB"mstr_discrete"
CDS_LOCATION"C3T7"
REUSE_ID"33"
CDS_SEC"1"
$SEC"1";
"A"
$PN"1"16;
"B"
$PN"2"14;
%"GND"
"1","(-475,3525)","0","mstr_symbols","I185";
;
SIZE"1B"
CDS_LIB"mstr_symbols"
VOLTAGE"0"
ROOM"PVPP_KLM_VR"
BOM_COST"PVPP_KLM_VR"
BODY_TYPE"PLUMBING"
HDL_POWER"GND";
"A\NAC"15;
%"CAP"
"1","(-475,3925)","0","mstr_discrete","I186";
;
LOCATION"C3T9"
PART_NUMBER"C95333-006"
VALUE"47UF"
TOLERANCE"20%"
PACK_TYPE"0805"
VOLTAGE"4V"
MATERIAL"X6S"
GROUP"PWR_MLCC_CAP"
$SEC"1"
CDS_SEC"1"
REUSE_ID"33"
CDS_LOCATION"C3T9"
ROOM"PVPP_KLM_VR"
CDS_LIB"mstr_discrete"
BOM_COST"PVPP_KLM_VR";
"A"
$PN"1"16;
"B"
$PN"2"15;
%"PVPP_ABC"
"1","(-400,4200)","0","mstr_symbols","I187";
;
HDL_POWER"PVPP_ABC"
BODY_TYPE"PLUMBING"
VOLTAGE"2.5V"
CDS_LIB"mstr_symbols"
BOM_COST"PVPP_KLM_VR"
ROOM"PVPP_KLM_VR";
"G\NAC"16;
%"AGND_SCSI"
"1","(-4025,2100)","0","mstr_symbols","I189";
;
HDL_POWER"AGND_PVPP_ABC"
BODY_TYPE"PLUMBING"
CDS_LIB"mstr_symbols"
VOLTAGE"0.0V"
BOM_COST"PVPP_KLM_VR"
ROOM"PVPP_KLM_VR";
"A"17;
%"AGND_SCSI"
"1","(-4400,1600)","0","mstr_symbols","I190";
;
HDL_POWER"AGND_PVPP_ABC"
BODY_TYPE"PLUMBING"
VOLTAGE"0"
CDS_LIB"mstr_symbols";
"A"18;
%"P3V3_STBY"
"1","(-3875,1775)","0","mstr_symbols","I192";
;
HDL_POWER"P3V3_STBY"
BODY_TYPE"PLUMBING"
SIZE"1B"
VOLTAGE"+3.3V"
CDS_LIB"mstr_symbols";
"G\NAC"19;
%"NCP3232L"
"1","(-3450,3125)","0","mstr_vreg","I193";
;
CDS_SEC"1"
PART_NUMBER"H86355-001"
MATERIAL"IC"
LOCATION"EU7F1"
SEC_TYPE"SM"
PACK_TYPE"SM"
SEC"1"
CDS_LOCATION"EU7F1"
CDS_LIB"mstr_vreg"
CDS_LMAN_SYM_OUTLINE"-450,850,450,-900";
"PG"
$PN"7"45;
"PGND<0>"
$PN"16"21;
"PGND<1>"
$PN"17"21;
"PGND<2>"
$PN"18"21;
"PGND<3>"
$PN"19"21;
"PGND<4>"
$PN"20"21;
"PGND<5>"
$PN"21"21;
"PGND<6>"
$PN"22"21;
"PGND<8>"
$PN"24"21;
"PGND<7>"
$PN"23"21;
"PGND<9>"
$PN"25"21;
"PGND<10>"
$PN"26"21;
"PGND<11>"
$PN"27"21;
"PGND<12>"
$PN"28"21;
"PGND<13>"
$PN"37"21;
"GND"
$PN"41"21;
"AGND"
$PN"5"17;
"EN"
$PN"40"32;
"SS"
$PN"1"43;
"ISET"
$PN"4"46;
"OTS"
$PN"6"23;
"VIN<6>"
$PN"14"31;
"VIN<7>"
$PN"42"31;
"VCC"
$PN"39"31;
"VIN<1>"
$PN"9"31;
"VIN<5>"
$PN"13"31;
"VIN<4>"
$PN"12"31;
"VIN<3>"
$PN"11"31;
"VIN<2>"
$PN"10"31;
"VIN<0>"
$PN"8"31;
"VB"
$PN"38"44;
"COMP"
$PN"3"35;
"FB"
$PN"2"33;
"VSWH<1>"
$PN"29"41;
"VSWH<0>"
$PN"15"41;
"VSW"
$PN"35"41;
"VSWH<2>"
$PN"30"41;
"VSWH<3>"
$PN"31"41;
"VSWH<4>"
$PN"32"41;
"VSWH<5>"
$PN"33"41;
"VSWH<6>"
$PN"34"41;
"BST"
$PN"36"42;
"VSWH<7>"
$PN"43"41;
%"CAP"
"1","(-4725,2425)","0","mstr_discrete","I194";
;
CDS_SEC"1"
VALUE"0.027UF"
VOLTAGE"16V"
PART_NUMBER"A36096-129"
TOLERANCE"10%"
MATERIAL"X7R"
LOCATION"C7F10"
PACK_TYPE"0402"
SEC"1"
SEC_TYPE"0402"
REUSE_ID"26"
BOM_COST"PVPP_KLM_VR"
ROOM"PVPP_KLM_VR"
CDS_LIB"mstr_discrete"
CDS_LOCATION"C7F10";
"A"
$PN"1"43;
"B"
$PN"2"20;
%"AGND_SCSI"
"1","(-4725,2200)","0","mstr_symbols","I195";
;
HDL_POWER"AGND_PVPP_ABC"
BODY_TYPE"PLUMBING"
VOLTAGE"0.0V"
CDS_LIB"mstr_symbols"
BOM_COST"PVPP_KLM_VR"
ROOM"PVPP_KLM_VR";
"A"20;
%"GND"
"1","(-2725,2175)","0","mstr_symbols","I196";
;
HDL_POWER"GND"
BODY_TYPE"PLUMBING"
SIZE"1B"
VOLTAGE"0"
CDS_LIB"mstr_symbols"
ROOM"PVPP_KLM_VR"
BOM_COST"PVPP_KLM_VR";
"A\NAC"21;
%"CAP"
"2","(-1875,3075)","2","mstr_discrete","I199";
;
CDS_SEC"1"
VALUE"100.0PF"
VOLTAGE"50V"
PART_NUMBER"A36095-026"
MATERIAL"COG"
PACK_TYPE"0402LF"
LOCATION"C7F9"
TOLERANCE"5%"
SEC_TYPE"0402LF"
REUSE_ID"27"
SEC"1"
CDS_LIB"mstr_discrete"
BOM_COST"PVPP_KLM_VR"
CDS_LOCATION"C7F9"
ROOM"PVPP_KLM_VR";
"A"
$PN"1"33;
"B"
$PN"2"35;
%"CAP"
"2","(-2500,2700)","2","mstr_discrete","I200";
;
CDS_SEC"1"
LOCATION"C7F12"
PART_NUMBER"A36096-075"
VALUE"2200PF"
PACK_TYPE"0402LF"
MATERIAL"X7R"
VOLTAGE"50V"
TOLERANCE"10%"
SEC_TYPE"0402LF"
CDS_LIB"mstr_discrete"
REUSE_ID"27"
BOM_COST"PVPP_KLM_VR"
SEC"1"
CDS_LOCATION"C7F12"
ROOM"PVPP_KLM_VR";
"A"
$PN"1"34;
"B"
$PN"2"35;
%"RES"
"1","(-1800,2700)","0","mstr_discrete","I201";
;
CDS_SEC"1"
VALUE"7.87K"
WATTAGE"1/16W"
MATERIAL"CHIP"
PACK_TYPE"0402"
TOLERANCE"1.0%"
LOCATION"R7F18"
PART_NUMBER"G21796-242"
REUSE_ID"13"
SEC"1"
SEC_TYPE"0402"
ROOM"PVPP_KLM_VR"
CDS_LOCATION"R7F18"
BOM_COST"PVPP_KLM_VR"
CDS_LIB"mstr_discrete";
"B"
$PN"2"33;
"A"
$PN"1"34;
%"CAP"
"1","(-5375,2625)","0","mstr_discrete","I202";
;
CDS_SEC"1"
CONFIG"078.47521.08BD"
LOCATION"C3T11"
PACK_TYPE"0603"
TOLERANCE"10%"
PART_NUMBER"E15431-003"
VOLTAGE"6.3V"
MATERIAL"X6S"
VALUE"4.7UF"
SEC"1"
REUSE_ID"26"
SEC_TYPE"0603"
BOM_COST"PVPP_KLM_VR"
CDS_LOCATION"C3T11"
CDS_LIB"mstr_discrete"
ROOM"PVPP_KLM_VR";
"A"
$PN"1"44;
"B"
$PN"2"22;
%"AGND_SCSI"
"1","(-5375,2325)","0","mstr_symbols","I203";
;
HDL_POWER"AGND_PVPP_ABC"
BODY_TYPE"PLUMBING"
CDS_LIB"mstr_symbols"
ROOM"PVPP_KLM_VR"
BOM_COST"PVPP_KLM_VR"
VOLTAGE"0.0V";
"A"22;
%"AGND_SCSI"
"1","(-5025,2950)","0","mstr_symbols","I204";
;
HDL_POWER"AGND_PVPP_ABC"
BODY_TYPE"PLUMBING"
CDS_LIB"mstr_symbols"
VOLTAGE"0.0V"
ROOM"PVPP_KLM_VR"
BOM_COST"PVPP_KLM_VR";
"A"23;
%"CAP_A"
"1","(-4775,3750)","0","dev_discrete","I205";
;
VALUE"0.1UF"
PACK_TYPE"0402V"
LOCATION"C7F6"
TOLERANCE"10%"
VOLTAGE"16V"
MATERIAL"X7R"
PART_NUMBER"A36096-030"
CDS_LOCATION"C7F6"
CDS_SEC"1"
SEC_TYPE"0402V"
SEC"1"
CDS_LIB"dev_discrete";
"B"
$PN"2"24;
"A"
$PN"1"31;
%"GND"
"1","(-4775,3525)","0","mstr_symbols","I206";
;
HDL_POWER"GND"
BODY_TYPE"PLUMBING"
VOLTAGE"0"
SIZE"1B"
CDS_LIB"mstr_symbols"
BOM_COST"PVPP_KLM_VR"
ROOM"PVPP_KLM_VR";
"A\NAC"24;
%"RES"
"1","(-3000,1225)","0","mstr_discrete","I208";
;
CDS_SEC"1"
MATERIAL"CHIP"
VALUE"22.1"
PACK_TYPE"0402"
PART_NUMBER"G21796-250"
LOCATION"R7F16"
TOLERANCE"1.0%"
WATTAGE"1/16W"
ROOM"PVPP_KLM_VR"
SEC_TYPE"0402"
SEC"1"
CDS_LOCATION"R7F16"
CDS_LIB"mstr_discrete";
"B"
$PN"2"38;
"A"
$PN"1"45;
%"CAP"
"1","(-6225,4375)","0","mstr_discrete","I209";
;
CDS_SEC"1"
PACK_TYPE"0805"
MATERIAL"X6S"
TOLERANCE"10%"
VOLTAGE"16V"
VALUE"10UF"
LOCATION"C7F5"
PART_NUMBER"C95333-007"
SEC_TYPE"0805"
CDS_LOCATION"C7F5"
SEC"1"
CDS_LIB"mstr_discrete";
"A"
$PN"1"31;
"B"
$PN"2"27;
%"CAP"
"1","(-5825,4375)","0","mstr_discrete","I210";
;
CDS_SEC"1"
VALUE"10UF"
LOCATION"C3T8"
PACK_TYPE"0805"
PART_NUMBER"C95333-007"
TOLERANCE"10%"
VOLTAGE"16V"
MATERIAL"X6S"
SEC_TYPE"0805"
SEC"1"
CDS_LOCATION"C3T8"
CDS_LIB"mstr_discrete";
"A"
$PN"1"31;
"B"
$PN"2"26;
%"CAP"
"1","(-5425,4375)","0","mstr_discrete","I211";
;
CDS_SEC"1"
LOCATION"C3T14"
VALUE"10UF"
PART_NUMBER"C95333-007"
TOLERANCE"10%"
VOLTAGE"16V"
MATERIAL"X6S"
PACK_TYPE"0805"
SEC_TYPE"0805"
CDS_LOCATION"C3T14"
SEC"1"
CDS_LIB"mstr_discrete";
"A"
$PN"1"31;
"B"
$PN"2"25;
%"GND"
"1","(-5425,4175)","0","mstr_symbols","I212";
;
HDL_POWER"GND"
BODY_TYPE"PLUMBING"
CDS_LIB"mstr_symbols"
SIZE"1B"
VOLTAGE"0"
ROOM"PVPP_KLM_VR"
BOM_COST"PVPP_KLM_VR";
"A\NAC"25;
%"GND"
"1","(-5825,4175)","0","mstr_symbols","I213";
;
HDL_POWER"GND"
BODY_TYPE"PLUMBING"
SIZE"1B"
CDS_LIB"mstr_symbols"
VOLTAGE"0"
ROOM"PVPP_KLM_VR"
BOM_COST"PVPP_KLM_VR";
"A\NAC"26;
%"GND"
"1","(-6225,4175)","0","mstr_symbols","I214";
;
HDL_POWER"GND"
BODY_TYPE"PLUMBING"
SIZE"1B"
CDS_LIB"mstr_symbols"
VOLTAGE"0"
ROOM"PVPP_KLM_VR"
BOM_COST"PVPP_KLM_VR";
"A\NAC"27;
%"CAP"
"1","(-5075,4375)","0","mstr_discrete","I215";
;
CDS_SEC"1"
VOLTAGE"16V"
VALUE"10UF"
LOCATION"C3T12"
MATERIAL"X6S"
PACK_TYPE"0805"
TOLERANCE"10%"
PART_NUMBER"C95333-007"
SEC_TYPE"0805"
SEC"1"
CDS_LOCATION"C3T12"
CDS_LIB"mstr_discrete";
"A"
$PN"1"31;
"B"
$PN"2"28;
%"GND"
"1","(-5075,4175)","0","mstr_symbols","I216";
;
HDL_POWER"GND"
BODY_TYPE"PLUMBING"
VOLTAGE"0"
SIZE"1B"
CDS_LIB"mstr_symbols"
ROOM"PVPP_KLM_VR"
BOM_COST"PVPP_KLM_VR";
"A\NAC"28;
%"CAPP"
"1","(-1100,3900)","0","mstr_discrete","I217";
;
CDS_SEC"1"
PACK_TYPE"7343"
VOLTAGE"4V"
TOLERANCE"20%"
VALUE"220UF"
LOCATION"C4T3"
MATERIAL"POSCAP"
PART_NUMBER"724613-067"
GROUP"PWR_BULK_CAP"
CDS_LIB"mstr_discrete"
CDS_LOCATION"C4T3"
SEC"1"
SEC_TYPE"7343";
"B"
$PN"2"13;
"A"
$PN"1"16;
%"RES"
"2","(-675,2800)","0","mstr_discrete","I218";
;
CDS_SEC"1"
PART_NUMBER"G85996-004"
MATERIAL"CHIP"
PACK_TYPE"0402"
WATTAGE"1/16W"
TOLERANCE"0.1%"
VALUE"1.0K"
LOCATION"R7F17"
CDS_LIB"mstr_discrete"
CDS_LOCATION"R7F17"
ROOM"PVPP_KLM_VR"
BOM_COST"PVPP_KLM_VR"
SPOF"TRUE"
SEC_TYPE"0402"
REUSE_ID"9"
SEC"1";
"A"
$PN"1"47;
"B"
$PN"2"37;
%"CAP"
"1","(-675,2000)","0","mstr_discrete","I219";
;
CDS_SEC"1"
PART_NUMBER"A36096-075"
MATERIAL"X7R"
TOLERANCE"10%"
VALUE"2200PF"
PACK_TYPE"0402LF"
LOCATION"C7F13"
VOLTAGE"50V"
BOM_COST"PVPP_KLM_VR"
CDS_LIB"mstr_discrete"
SEC"1"
CDS_LOCATION"C7F13"
ROOM"PVPP_KLM_VR"
REUSE_ID"26"
SPOF"TRUE"
SEC_TYPE"0402LF";
"A"
$PN"1"37;
"B"
$PN"2"33;
%"RES"
"1","(-5775,3075)","0","mstr_discrete","I220";
;
CDS_SEC"1"
LOCATION"R7F9"
PART_NUMBER"G21497-005"
TOLERANCE"5%"
VALUE"0.0"
WATTAGE"1/16W"
MATERIAL"CHIP"
PACK_TYPE"0402"
ROOM"PVCCIN_CPU0_VR"
CDS_LOCATION"R7F9"
SEC"1"
SEC_TYPE"0402"
CDS_LIB"mstr_discrete";
"B"
$PN"2"32;
"A"
$PN"1"36;
%"GND"
"1","(-6650,4150)","0","mstr_symbols","I222";
;
HDL_POWER"GND"
BODY_TYPE"PLUMBING"
CDS_LIB"mstr_symbols"
BOM_COST"PVPP_KLM_VR"
ROOM"PVPP_KLM_VR"
VOLTAGE"0"
SIZE"1B";
"A\NAC"29;
%"SC22U16V5MX-4-GP"
"1","(-6650,4325)","0","w_hdl","I225";
;
CDS_SEC"1"
CDS_LOCATION"C22W10"
PACK_SIZE"0805"
TYPE"X6S"
RATED"16V"
TOLERANCE"20%"
ATTRIBUTE"22UF"
LOCATION"C22W10"
VALUE"SC22U16V5MX-4-GP"
PACK_TYPE"SMD-BCG5"
SEC"1"
SEC_TYPE"SMD-BCG5"
PART_NUMBER"078.22611.0811"
CDS_LIB"w_hdl"
CDS_LMAN_SYM_OUTLINE"-50,25,50,-25";
"2"
$PN"2"29;
"1"
$PN"1"31;
%"SC22U16V5MX-4-GP"
"1","(-6950,4325)","0","w_hdl","I226";
;
CDS_SEC"1"
CDS_LOCATION"C7F7"
PACK_SIZE"0805"
TYPE"X6S"
RATED"16V"
TOLERANCE"20%"
ATTRIBUTE"22UF"
LOCATION"C7F7"
VALUE"SC22U16V5MX-4-GP"
PACK_TYPE"SMD-BCG5"
SEC"1"
SEC_TYPE"SMD-BCG5"
PART_NUMBER"078.22611.0811"
CDS_LIB"w_hdl"
CDS_LMAN_SYM_OUTLINE"-50,25,50,-25";
"2"
$PN"2"30;
"1"
$PN"1"31;
%"GND"
"1","(-6950,4150)","0","mstr_symbols","I228";
;
HDL_POWER"GND"
BODY_TYPE"PLUMBING"
CDS_LIB"mstr_symbols"
BOM_COST"PVPP_KLM_VR"
ROOM"PVPP_KLM_VR"
VOLTAGE"0"
SIZE"1B";
"A\NAC"30;
%"RES"
"1","(-3800,4450)","0","mstr_discrete","I229";
;
PACK_TYPE"0603"
VALUE"0"
LOCATION"R7F8"
MATERIAL"CHIP"
PART_NUMBER"G22178-002"
TOLERANCE"5.0%"
WATTAGE"1/10W"
CDS_LOCATION"R7F8"
ROOM"NIC_SPRV"
BOM_COST"NT_GBE_BASE"
CDS_LIB"mstr_discrete"
SEC_TYPE"0603"
SEC"1"
CDS_SEC"1";
"B"
$PN"2"39;
"A"
$PN"1"42;
%"RES"
"2","(-1000,1550)","0","mstr_discrete","I230";
;
PACK_TYPE"0402"
PART_NUMBER"G21796-161"
MATERIAL"CHIP"
WATTAGE"1/16W"
TOLERANCE"1%"
VALUE"6.19K"
LOCATION"R7F11"
BOM_COST"IO_SLOT"
SEC"1"
SEC_TYPE"0402"
ROOM"IO_SLOT"
CDS_LIB"mstr_discrete"
CDS_SEC"1"
CDS_LOCATION"R7F11";
"A"
$PN"1"33;
"B"
$PN"2"8;
END.
